G04*
G04 #@! TF.GenerationSoftware,Altium Limited,Altium Designer,23.0.1 (38)*
G04*
G04 Layer_Color=32768*
%FSLAX25Y25*%
%MOIN*%
G70*
G04*
G04 #@! TF.SameCoordinates,C48E81DB-6E20-4E2D-80E6-7C5AFAA1A21F*
G04*
G04*
G04 #@! TF.FilePolarity,Positive*
G04*
G01*
G75*
M02*
